(kicad_pcb
	(version 20260206)
	(generator "pcbnew")
	(generator_version "10.0")
	(general
		(thickness 1.6)
		(legacy_teardrops no)
	)
	(paper "A4")
	(title_block
		(title "peb — Lightning_PEB_BRD.brd")
		(comment 1 "Lightning (Wiwynn / Facebook NVMe JBOF) / footprints 1964-1971 of 2563")
	)
	(layers
		(0 "F.Cu" signal "TOP")
		(4 "In1.Cu" signal "L2GND")
		(6 "In2.Cu" signal "L3")
		(8 "In3.Cu" signal "L4VCC")
		(10 "In4.Cu" signal "L5VCC")
		(12 "In5.Cu" signal "L6")
		(14 "In6.Cu" signal "L7GND")
		(2 "B.Cu" signal "BOTTOM")
		(9 "F.Adhes" user "F.Adhesive")
		(11 "B.Adhes" user "B.Adhesive")
		(13 "F.Paste" user "Package Geometry/Pastemask Top")
		(15 "B.Paste" user "Package Geometry/Pastemask Bottom")
		(5 "F.SilkS" user "Ref Des/Silkscreen Top")
		(7 "B.SilkS" user "Ref Des/Silkscreen Bottom")
		(1 "F.Mask" user "Board Geometry/Soldermask Top")
		(3 "B.Mask" user "Board Geometry/Soldermask Bottom")
		(17 "Dwgs.User" user "User.Drawings")
		(19 "Cmts.User" user "User.Comments")
		(21 "Eco1.User" user "User.Eco1")
		(23 "Eco2.User" user "User.Eco2")
		(25 "Edge.Cuts" user "Board Geometry/Outline")
		(27 "Margin" user)
		(31 "F.CrtYd" user "Package Geometry/Place Bound Top")
		(29 "B.CrtYd" user "Package Geometry/Place Bound Bottom")
		(35 "F.Fab" user "Ref Des/Assembly Top")
		(33 "B.Fab" user "Ref Des/Assembly Bottom")
	)
	(footprint ""
		(layer "B.Cu")
		(at 221.7674 -7.366)
		(property "Reference" "R3714"
			(at 0 0 0)
			(layer "B.SilkS")
			(hide yes)
			(effects
				(font
					(size 1.27 1.27)
				)
				(justify mirror)
			)
		)
		(property "Value" "1KR2F-3-GP"
			(at -0.064008 -3.993896 0)
			(unlocked yes)
			(layer "B.Fab")
			(hide yes)
			(effects
				(font
					(size 1.016 1.016)
					(thickness 0.1524)
				)
				(justify mirror)
			)
		)
		(property "Device Type" "R402H16"
			(at -0.064008 -5.517896 0)
			(unlocked yes)
			(layer "B.Fab")
			(hide yes)
			(effects
				(font
					(size 1.016 1.016)
					(thickness 0.1524)
				)
				(justify mirror)
			)
		)
		(duplicate_pad_numbers_are_jumpers no)
		(fp_line
			(start -0.508 -0.9398)
			(end 0.508 -0.9398)
			(stroke
				(width 0.1524)
				(type default)
			)
			(layer "B.SilkS")
		)
		(fp_line
			(start 0.508 -0.9398)
			(end 0.508 0.9398)
			(stroke
				(width 0.1524)
				(type default)
			)
			(layer "B.SilkS")
		)
		(fp_rect
			(start 0.508 0.9398)
			(end -0.508 -0.9398)
			(stroke
				(width 0)
				(type default)
			)
			(fill no)
			(layer "B.CrtYd")
		)
		(fp_rect
			(start 0.508 0.9398)
			(end -0.508 -0.9398)
			(stroke
				(width 0)
				(type default)
			)
			(fill no)
			(layer "B.Fab")
		)
		(pad "1" smd custom
			(at 0 -0.4445 180)
			(size 0.1397 0.1397)
			(layers "B.Cu" "B.Mask" "B.Paste")
			(net "HOST1_RST_N")
			(options
				(clearance outline)
				(anchor circle)
			)
			(primitives
				(gr_poly
					(pts
						(arc
							(start -0.1778 0.2794)
							(mid -0.249642 0.249642)
							(end -0.2794 0.1778)
						)
						(arc
							(start -0.2794 -0.1778)
							(mid -0.249642 -0.249642)
							(end -0.1778 -0.2794)
						)
						(arc
							(start 0.1778 -0.2794)
							(mid 0.249642 -0.249642)
							(end 0.2794 -0.1778)
						)
						(arc
							(start 0.2794 0.1778)
							(mid 0.249642 0.249642)
							(end 0.1778 0.2794)
						)
					)
					(width 0)
					(fill yes)
				)
			)
		)
		(pad "2" smd custom
			(at 0 0.4445 180)
			(size 0.1397 0.1397)
			(layers "B.Cu" "B.Mask" "B.Paste")
			(net "P3V3_STBY")
			(options
				(clearance outline)
				(anchor circle)
			)
			(primitives
				(gr_poly
					(pts
						(arc
							(start -0.1778 0.2794)
							(mid -0.249642 0.249642)
							(end -0.2794 0.1778)
						)
						(arc
							(start -0.2794 -0.1778)
							(mid -0.249642 -0.249642)
							(end -0.1778 -0.2794)
						)
						(arc
							(start 0.1778 -0.2794)
							(mid 0.249642 -0.249642)
							(end 0.2794 -0.1778)
						)
						(arc
							(start 0.2794 0.1778)
							(mid 0.249642 0.249642)
							(end 0.1778 0.2794)
						)
					)
					(width 0)
					(fill yes)
				)
			)
		)
	)
	(footprint ""
		(layer "B.Cu")
		(at 245.5926 -56.9976 -90)
		(property "Reference" "C512"
			(at 0 0 90)
			(layer "B.SilkS")
			(hide yes)
			(effects
				(font
					(size 1.27 1.27)
				)
				(justify mirror)
			)
		)
		(property "Value" "SCD1U16V1KX-1-GP"
			(at 2.8321 -1.7399 270)
			(unlocked yes)
			(layer "B.Fab")
			(hide yes)
			(effects
				(font
					(size 1.016 1.016)
					(thickness 0.1524)
				)
				(justify mirror)
			)
		)
		(property "Device Type" "C0201H13"
			(at 2.8321 -3.2639 270)
			(unlocked yes)
			(layer "B.Fab")
			(hide yes)
			(effects
				(font
					(size 1.016 1.016)
					(thickness 0.1524)
				)
				(justify mirror)
			)
		)
		(duplicate_pad_numbers_are_jumpers no)
		(fp_rect
			(start 0.2794 0.6477)
			(end -0.2794 -0.6477)
			(stroke
				(width 0)
				(type default)
			)
			(fill no)
			(layer "B.CrtYd")
		)
		(fp_rect
			(start 0.2794 0.6477)
			(end -0.2794 -0.6477)
			(stroke
				(width 0)
				(type default)
			)
			(fill no)
			(layer "B.Fab")
		)
		(pad "1" smd custom
			(at 0 -0.2794 90)
			(size 0.0762 0.0762)
			(layers "B.Cu" "B.Mask" "B.Paste")
			(net "DUT_AVD_TX")
			(options
				(clearance outline)
				(anchor circle)
			)
			(primitives
				(gr_poly
					(pts
						(arc
							(start 0.1524 0.127)
							(mid 0.137521 0.162921)
							(end 0.1016 0.1778)
						)
						(arc
							(start -0.1016 0.1778)
							(mid -0.137521 0.162921)
							(end -0.1524 0.127)
						)
						(arc
							(start -0.1524 -0.127)
							(mid -0.137521 -0.162921)
							(end -0.1016 -0.1778)
						)
						(arc
							(start 0.1016 -0.1778)
							(mid 0.137521 -0.162921)
							(end 0.1524 -0.127)
						)
					)
					(width 0)
					(fill yes)
				)
			)
		)
		(pad "2" smd custom
			(at 0 0.2794 90)
			(size 0.0762 0.0762)
			(layers "B.Cu" "B.Mask" "B.Paste")
			(net "GND")
			(options
				(clearance outline)
				(anchor circle)
			)
			(primitives
				(gr_poly
					(pts
						(arc
							(start 0.1524 0.127)
							(mid 0.137521 0.162921)
							(end 0.1016 0.1778)
						)
						(arc
							(start -0.1016 0.1778)
							(mid -0.137521 0.162921)
							(end -0.1524 0.127)
						)
						(arc
							(start -0.1524 -0.127)
							(mid -0.137521 -0.162921)
							(end -0.1016 -0.1778)
						)
						(arc
							(start 0.1016 -0.1778)
							(mid 0.137521 -0.162921)
							(end 0.1524 -0.127)
						)
					)
					(width 0)
					(fill yes)
				)
			)
		)
	)
	(footprint ""
		(layer "B.Cu")
		(at 39.586154 -158.987744 180)
		(property "Reference" "C173"
			(at 0 0 0)
			(layer "B.SilkS")
			(hide yes)
			(effects
				(font
					(size 1.27 1.27)
				)
				(justify mirror)
			)
		)
		(property "Value" "SCD1U16V2KX-3GP"
			(at -1.1811 -2.7051 180)
			(unlocked yes)
			(layer "B.Fab")
			(hide yes)
			(effects
				(font
					(size 1.016 1.016)
					(thickness 0.1524)
				)
				(justify mirror)
			)
		)
		(property "Device Type" "C402H22"
			(at -1.1811 -4.2291 180)
			(unlocked yes)
			(layer "B.Fab")
			(hide yes)
			(effects
				(font
					(size 1.016 1.016)
					(thickness 0.1524)
				)
				(justify mirror)
			)
		)
		(duplicate_pad_numbers_are_jumpers no)
		(fp_rect
			(start 0.4318 0.9525)
			(end -0.4318 -0.9525)
			(stroke
				(width 0)
				(type default)
			)
			(fill no)
			(layer "B.CrtYd")
		)
		(fp_rect
			(start 0.4318 0.9525)
			(end -0.4318 -0.9525)
			(stroke
				(width 0)
				(type default)
			)
			(fill no)
			(layer "B.Fab")
		)
		(pad "1" smd custom
			(at 0 -0.4445)
			(size 0.1524 0.1524)
			(layers "B.Cu" "B.Mask" "B.Paste")
			(net "P1V53_STBY")
			(options
				(clearance outline)
				(anchor circle)
			)
			(primitives
				(gr_poly
					(pts
						(arc
							(start 0.3048 0.2032)
							(mid 0.275042 0.275042)
							(end 0.2032 0.3048)
						)
						(arc
							(start -0.2032 0.3048)
							(mid -0.275042 0.275042)
							(end -0.3048 0.2032)
						)
						(arc
							(start -0.3048 -0.2032)
							(mid -0.275042 -0.275042)
							(end -0.2032 -0.3048)
						)
						(arc
							(start 0.2032 -0.3048)
							(mid 0.275042 -0.275042)
							(end 0.3048 -0.2032)
						)
					)
					(width 0)
					(fill yes)
				)
			)
		)
		(pad "2" smd custom
			(at 0 0.4445)
			(size 0.1524 0.1524)
			(layers "B.Cu" "B.Mask" "B.Paste")
			(net "GND")
			(options
				(clearance outline)
				(anchor circle)
			)
			(primitives
				(gr_poly
					(pts
						(arc
							(start 0.3048 0.2032)
							(mid 0.275042 0.275042)
							(end 0.2032 0.3048)
						)
						(arc
							(start -0.2032 0.3048)
							(mid -0.275042 0.275042)
							(end -0.3048 0.2032)
						)
						(arc
							(start -0.3048 -0.2032)
							(mid -0.275042 -0.275042)
							(end -0.2032 -0.3048)
						)
						(arc
							(start 0.2032 -0.3048)
							(mid 0.275042 -0.275042)
							(end 0.3048 -0.2032)
						)
					)
					(width 0)
					(fill yes)
				)
			)
		)
	)
	(footprint ""
		(layer "B.Cu")
		(at 34.798 -116.713 180)
		(property "Reference" "R506"
			(at 0 0 0)
			(layer "B.SilkS")
			(hide yes)
			(effects
				(font
					(size 1.27 1.27)
				)
				(justify mirror)
			)
		)
		(property "Value" "0R2J-2-GP"
			(at -0.064008 -3.993896 180)
			(unlocked yes)
			(layer "B.Fab")
			(hide yes)
			(effects
				(font
					(size 1.016 1.016)
					(thickness 0.1524)
				)
				(justify mirror)
			)
		)
		(property "Device Type" "R402H16"
			(at -0.064008 -5.517896 180)
			(unlocked yes)
			(layer "B.Fab")
			(hide yes)
			(effects
				(font
					(size 1.016 1.016)
					(thickness 0.1524)
				)
				(justify mirror)
			)
		)
		(duplicate_pad_numbers_are_jumpers no)
		(fp_line
			(start 0.508 -0.9398)
			(end 0.508 0.9398)
			(stroke
				(width 0.1524)
				(type default)
			)
			(layer "B.SilkS")
		)
		(fp_line
			(start -0.508 -0.9398)
			(end 0.508 -0.9398)
			(stroke
				(width 0.1524)
				(type default)
			)
			(layer "B.SilkS")
		)
		(fp_rect
			(start 0.508 0.9398)
			(end -0.508 -0.9398)
			(stroke
				(width 0)
				(type default)
			)
			(fill no)
			(layer "B.CrtYd")
		)
		(fp_rect
			(start 0.508 0.9398)
			(end -0.508 -0.9398)
			(stroke
				(width 0)
				(type default)
			)
			(fill no)
			(layer "B.Fab")
		)
		(pad "1" smd custom
			(at 0 -0.4445)
			(size 0.1397 0.1397)
			(layers "B.Cu" "B.Mask" "B.Paste")
			(net "BMC_ADD2")
			(options
				(clearance outline)
				(anchor circle)
			)
			(primitives
				(gr_poly
					(pts
						(arc
							(start -0.1778 0.2794)
							(mid -0.249642 0.249642)
							(end -0.2794 0.1778)
						)
						(arc
							(start -0.2794 -0.1778)
							(mid -0.249642 -0.249642)
							(end -0.1778 -0.2794)
						)
						(arc
							(start 0.1778 -0.2794)
							(mid 0.249642 -0.249642)
							(end 0.2794 -0.1778)
						)
						(arc
							(start 0.2794 0.1778)
							(mid 0.249642 0.249642)
							(end 0.1778 0.2794)
						)
					)
					(width 0)
					(fill yes)
				)
			)
		)
		(pad "2" smd custom
			(at 0 0.4445)
			(size 0.1397 0.1397)
			(layers "B.Cu" "B.Mask" "B.Paste")
			(net "BMC_ADD2_R")
			(options
				(clearance outline)
				(anchor circle)
			)
			(primitives
				(gr_poly
					(pts
						(arc
							(start -0.1778 0.2794)
							(mid -0.249642 0.249642)
							(end -0.2794 0.1778)
						)
						(arc
							(start -0.2794 -0.1778)
							(mid -0.249642 -0.249642)
							(end -0.1778 -0.2794)
						)
						(arc
							(start 0.1778 -0.2794)
							(mid 0.249642 -0.249642)
							(end 0.2794 -0.1778)
						)
						(arc
							(start 0.2794 0.1778)
							(mid 0.249642 0.249642)
							(end 0.1778 0.2794)
						)
					)
					(width 0)
					(fill yes)
				)
			)
		)
	)
	(footprint ""
		(layer "B.Cu")
		(at 247.651016 -26.694638 90)
		(property "Reference" "TP304"
			(at 0 0 90)
			(layer "B.SilkS")
			(hide yes)
			(effects
				(font
					(size 1.27 1.27)
				)
				(justify mirror)
			)
		)
		(property "Value" "TPAD28-2-GP"
			(at 0.0127 -1.6637 90)
			(unlocked yes)
			(layer "B.Fab")
			(hide yes)
			(effects
				(font
					(size 1.016 1.016)
					(thickness 0.1524)
				)
				(justify mirror)
			)
		)
		(property "Device Type" "TPAD28"
			(at 0.0127 -3.1877 90)
			(unlocked yes)
			(layer "B.Fab")
			(hide yes)
			(effects
				(font
					(size 1.016 1.016)
					(thickness 0.1524)
				)
				(justify mirror)
			)
		)
		(duplicate_pad_numbers_are_jumpers no)
		(fp_poly
			(pts
				(arc
					(start 0 0.3556)
					(mid 0 -0.3556)
					(end 0 0.3556)
				)
			)
			(stroke
				(width 0)
				(type default)
			)
			(fill no)
			(layer "B.CrtYd")
		)
		(fp_poly
			(pts
				(arc
					(start 0 0.6096)
					(mid 0 -0.6096)
					(end 0 0.6096)
				)
			)
			(stroke
				(width 0)
				(type default)
			)
			(fill no)
			(layer "B.Fab")
		)
		(pad "1" smd circle
			(at 0 0 270)
			(size 0.7112 0.7112)
			(layers "B.Cu" "B.Mask" "B.Paste")
			(net "TWI_SDA10")
		)
	)
	(footprint ""
		(layer "B.Cu")
		(at 223.851724 -190.601092)
		(property "Reference" "R4139"
			(at 0 0 0)
			(layer "B.SilkS")
			(hide yes)
			(effects
				(font
					(size 1.27 1.27)
				)
				(justify mirror)
			)
		)
		(property "Value" "4K7R2F-GP"
			(at -0.064008 -3.993896 0)
			(unlocked yes)
			(layer "B.Fab")
			(hide yes)
			(effects
				(font
					(size 1.016 1.016)
					(thickness 0.1524)
				)
				(justify mirror)
			)
		)
		(property "Device Type" "R402H16"
			(at -0.064008 -5.517896 0)
			(unlocked yes)
			(layer "B.Fab")
			(hide yes)
			(effects
				(font
					(size 1.016 1.016)
					(thickness 0.1524)
				)
				(justify mirror)
			)
		)
		(duplicate_pad_numbers_are_jumpers no)
		(fp_line
			(start -0.508 -0.9398)
			(end 0.508 -0.9398)
			(stroke
				(width 0.1524)
				(type default)
			)
			(layer "B.SilkS")
		)
		(fp_line
			(start 0.508 -0.9398)
			(end 0.508 0.9398)
			(stroke
				(width 0.1524)
				(type default)
			)
			(layer "B.SilkS")
		)
		(fp_rect
			(start 0.508 0.9398)
			(end -0.508 -0.9398)
			(stroke
				(width 0)
				(type default)
			)
			(fill no)
			(layer "B.CrtYd")
		)
		(fp_rect
			(start 0.508 0.9398)
			(end -0.508 -0.9398)
			(stroke
				(width 0)
				(type default)
			)
			(fill no)
			(layer "B.Fab")
		)
		(pad "1" smd custom
			(at 0 -0.4445 180)
			(size 0.1397 0.1397)
			(layers "B.Cu" "B.Mask" "B.Paste")
			(net "SSD_PERST#3")
			(options
				(clearance outline)
				(anchor circle)
			)
			(primitives
				(gr_poly
					(pts
						(arc
							(start -0.1778 0.2794)
							(mid -0.249642 0.249642)
							(end -0.2794 0.1778)
						)
						(arc
							(start -0.2794 -0.1778)
							(mid -0.249642 -0.249642)
							(end -0.1778 -0.2794)
						)
						(arc
							(start 0.1778 -0.2794)
							(mid 0.249642 -0.249642)
							(end 0.2794 -0.1778)
						)
						(arc
							(start 0.2794 0.1778)
							(mid 0.249642 0.249642)
							(end 0.1778 0.2794)
						)
					)
					(width 0)
					(fill yes)
				)
			)
		)
		(pad "2" smd custom
			(at 0 0.4445 180)
			(size 0.1397 0.1397)
			(layers "B.Cu" "B.Mask" "B.Paste")
			(net "P3V3_STBY")
			(options
				(clearance outline)
				(anchor circle)
			)
			(primitives
				(gr_poly
					(pts
						(arc
							(start -0.1778 0.2794)
							(mid -0.249642 0.249642)
							(end -0.2794 0.1778)
						)
						(arc
							(start -0.2794 -0.1778)
							(mid -0.249642 -0.249642)
							(end -0.1778 -0.2794)
						)
						(arc
							(start 0.1778 -0.2794)
							(mid 0.249642 -0.249642)
							(end 0.2794 -0.1778)
						)
						(arc
							(start 0.2794 0.1778)
							(mid 0.249642 0.249642)
							(end 0.1778 0.2794)
						)
					)
					(width 0)
					(fill yes)
				)
			)
		)
	)
	(footprint ""
		(layer "B.Cu")
		(at 35.687 -114.55146 180)
		(property "Reference" "R620"
			(at 0 0 0)
			(layer "B.SilkS")
			(hide yes)
			(effects
				(font
					(size 1.27 1.27)
				)
				(justify mirror)
			)
		)
		(property "Value" "0R2J-2-GP"
			(at -0.064008 -3.993896 180)
			(unlocked yes)
			(layer "B.Fab")
			(hide yes)
			(effects
				(font
					(size 1.016 1.016)
					(thickness 0.1524)
				)
				(justify mirror)
			)
		)
		(property "Device Type" "R402H16"
			(at -0.064008 -5.517896 180)
			(unlocked yes)
			(layer "B.Fab")
			(hide yes)
			(effects
				(font
					(size 1.016 1.016)
					(thickness 0.1524)
				)
				(justify mirror)
			)
		)
		(duplicate_pad_numbers_are_jumpers no)
		(fp_line
			(start 0.508 -0.9398)
			(end 0.508 0.9398)
			(stroke
				(width 0.1524)
				(type default)
			)
			(layer "B.SilkS")
		)
		(fp_line
			(start -0.508 -0.9398)
			(end 0.508 -0.9398)
			(stroke
				(width 0.1524)
				(type default)
			)
			(layer "B.SilkS")
		)
		(fp_rect
			(start 0.508 0.9398)
			(end -0.508 -0.9398)
			(stroke
				(width 0)
				(type default)
			)
			(fill no)
			(layer "B.CrtYd")
		)
		(fp_rect
			(start 0.508 0.9398)
			(end -0.508 -0.9398)
			(stroke
				(width 0)
				(type default)
			)
			(fill no)
			(layer "B.Fab")
		)
		(pad "1" smd custom
			(at 0 -0.4445)
			(size 0.1397 0.1397)
			(layers "B.Cu" "B.Mask" "B.Paste")
			(net "GND")
			(options
				(clearance outline)
				(anchor circle)
			)
			(primitives
				(gr_poly
					(pts
						(arc
							(start -0.1778 0.2794)
							(mid -0.249642 0.249642)
							(end -0.2794 0.1778)
						)
						(arc
							(start -0.2794 -0.1778)
							(mid -0.249642 -0.249642)
							(end -0.1778 -0.2794)
						)
						(arc
							(start 0.1778 -0.2794)
							(mid 0.249642 -0.249642)
							(end 0.2794 -0.1778)
						)
						(arc
							(start 0.2794 0.1778)
							(mid 0.249642 0.249642)
							(end 0.1778 0.2794)
						)
					)
					(width 0)
					(fill yes)
				)
			)
		)
		(pad "2" smd custom
			(at 0 0.4445)
			(size 0.1397 0.1397)
			(layers "B.Cu" "B.Mask" "B.Paste")
			(net "RMII_BMC_PHY_TXD1")
			(options
				(clearance outline)
				(anchor circle)
			)
			(primitives
				(gr_poly
					(pts
						(arc
							(start -0.1778 0.2794)
							(mid -0.249642 0.249642)
							(end -0.2794 0.1778)
						)
						(arc
							(start -0.2794 -0.1778)
							(mid -0.249642 -0.249642)
							(end -0.1778 -0.2794)
						)
						(arc
							(start 0.1778 -0.2794)
							(mid 0.249642 -0.249642)
							(end 0.2794 -0.1778)
						)
						(arc
							(start 0.2794 0.1778)
							(mid 0.249642 0.249642)
							(end 0.1778 0.2794)
						)
					)
					(width 0)
					(fill yes)
				)
			)
		)
	)
	(footprint ""
		(layer "B.Cu")
		(at 178.0794 -69.215)
		(property "Reference" "PG17"
			(at 0 0 0)
			(layer "B.SilkS")
			(hide yes)
			(effects
				(font
					(size 1.27 1.27)
				)
				(justify mirror)
			)
		)
		(property "Value" "GAP-CLOSE-PWR-3-GP"
			(at -0.0254 -6.5786 0)
			(unlocked yes)
			(layer "B.Fab")
			(hide yes)
			(effects
				(font
					(size 1.016 1.016)
					(thickness 0.1524)
				)
				(justify mirror)
			)
		)
		(property "Device Type" "GAP-CLOSE-PWR-3"
			(at -0.0254 -8.255 0)
			(unlocked yes)
			(layer "B.Fab")
			(hide yes)
			(effects
				(font
					(size 1.016 1.016)
					(thickness 0.1524)
				)
				(justify mirror)
			)
		)
		(duplicate_pad_numbers_are_jumpers no)
		(fp_rect
			(start 0.7112 0.4572)
			(end -0.7112 -0.4572)
			(stroke
				(width 0)
				(type default)
			)
			(fill no)
			(layer "B.CrtYd")
		)
		(fp_poly
			(pts
				(xy 0.7112 -0.4572) (xy -0.7112 -0.4572) (xy -0.7112 0.4572) (xy 0.7112 0.4572)
			)
			(stroke
				(width 0)
				(type default)
			)
			(fill no)
			(layer "B.Fab")
		)
		(pad "1" smd rect
			(at 0.3048 0 180)
			(size 0.6604 0.762)
			(layers "B.Cu" "B.Mask" "B.Paste")
			(net "DUT_AVD_PCIE")
		)
		(pad "2" smd rect
			(at -0.3048 0 180)
			(size 0.6604 0.762)
			(layers "B.Cu" "B.Mask" "B.Paste")
			(net "P0V9")
		)
	)
)
